(kicad_pcb
	(version 20241229)
	(generator "pcbnew")
	(generator_version "9.0")
	(general
		(thickness 1.599998)
		(legacy_teardrops no)
	)
	(paper "A4")
	(title_block
		(date "2023-02-12")
		(rev "1.1.5")
		(comment 9 "footprints 106-107 of 473")
	)
	(layers
		(0 "F.Cu" signal)
		(4 "In1.Cu" power "In1.GND")
		(6 "In2.Cu" signal)
		(8 "In3.Cu" power "In3.GND")
		(10 "In4.Cu" power "In4.VCC")
		(12 "In5.Cu" signal)
		(14 "In6.Cu" power "In6.VCC")
		(2 "B.Cu" signal)
		(9 "F.Adhes" user "F.Adhesive")
		(11 "B.Adhes" user "B.Adhesive")
		(13 "F.Paste" user)
		(15 "B.Paste" user)
		(5 "F.SilkS" user "F.Silkscreen")
		(7 "B.SilkS" user "B.Silkscreen")
		(1 "F.Mask" user)
		(3 "B.Mask" user)
		(17 "Dwgs.User" user "User.Drawings")
		(19 "Cmts.User" user "User.Comments")
		(21 "Eco1.User" user "User.Eco1")
		(23 "Eco2.User" user "User.Eco2")
		(25 "Edge.Cuts" user)
		(27 "Margin" user)
		(31 "F.CrtYd" user "F.Courtyard")
		(29 "B.CrtYd" user "B.Courtyard")
		(35 "F.Fab" user)
		(33 "B.Fab" user)
	)
	(footprint "antmicro-footprints:R_0402_1005Metric"
		(layer "F.Cu")
		(at 147.8026 92.201 -90)
		(descr "Resistor SMD 0402")
		(tags "resistor SMD 0402")
		(property "Reference" "R2"
			(at -0.701 -0.3974 270)
			(layer "F.SilkS")
			(effects
				(font
					(size 0.7 0.7)
					(thickness 0.15)
				)
				(justify left bottom)
			)
		)
		(property "Value" "R_10k_0402"
			(at 0 1.4 270)
			(layer "F.Fab")
			(effects
				(font
					(size 0.7 0.7)
					(thickness 0.15)
				)
				(justify left bottom)
			)
		)
		(property "Description" "10k resistor in 0402 package with 1% tolerance"
			(at 0 0 270)
			(layer "F.Fab")
			(hide yes)
			(effects
				(font
					(size 1.27 1.27)
					(thickness 0.15)
				)
			)
		)
		(property "Author" "Antmicro"
			(at 55.6016 240.0036 0)
			(layer "F.Fab")
			(hide yes)
			(effects
				(font
					(size 1 1)
					(thickness 0.15)
				)
			)
		)
		(property "License" "Apache-2.0"
			(at 55.6016 240.0036 0)
			(layer "F.Fab")
			(hide yes)
			(effects
				(font
					(size 1 1)
					(thickness 0.15)
				)
			)
		)
		(property "MPN" "CR0402-FX-1002GLF"
			(at 55.6016 240.0036 0)
			(layer "F.Fab")
			(hide yes)
			(effects
				(font
					(size 1 1)
					(thickness 0.15)
				)
			)
		)
		(property "Manufacturer" "Bourns"
			(at 55.6016 240.0036 0)
			(layer "F.Fab")
			(hide yes)
			(effects
				(font
					(size 1 1)
					(thickness 0.15)
				)
			)
		)
		(property "Tolerance" "1%"
			(at 55.6016 240.0036 0)
			(layer "F.Fab")
			(hide yes)
			(effects
				(font
					(size 1 1)
					(thickness 0.15)
				)
			)
		)
		(property "Val" "10k"
			(at 55.6016 240.0036 0)
			(layer "F.Fab")
			(hide yes)
			(effects
				(font
					(size 1 1)
					(thickness 0.15)
				)
			)
		)
		(sheetname "HyperRAM")
		(sheetfile "hyperram.kicad_sch")
		(attr smd)
		(fp_rect
			(start -0.93 -0.47)
			(end 0.93 0.47)
			(stroke
				(width 0.05)
				(type solid)
			)
			(fill no)
			(layer "F.CrtYd")
		)
		(fp_rect
			(start -0.5 -0.25)
			(end 0.5 0.25)
			(stroke
				(width 0.15)
				(type solid)
			)
			(fill no)
			(layer "F.Fab")
		)
		(pad "1" smd roundrect
			(at -0.485 0 270)
			(size 0.59 0.64)
			(layers "F.Cu" "F.Mask" "F.Paste")
			(roundrect_rratio 0.25)
			(net 459 "3V3_SYS")
			(pintype "passive")
		)
		(pad "2" smd roundrect
			(at 0.485 0 270)
			(size 0.59 0.64)
			(layers "F.Cu" "F.Mask" "F.Paste")
			(roundrect_rratio 0.25)
			(net 489 "HR_CS")
			(pintype "passive")
		)
	)
	(footprint "antmicro-footprints:FBGA-25-24_6x8mm_Layout5x5_P1mm"
		(layer "F.Cu")
		(at 150.696328 97.276157 90)
		(property "Reference" "U1"
			(at -0.723843 -4.196328 90)
			(layer "F.SilkS")
			(effects
				(font
					(size 0.7 0.7)
					(thickness 0.15)
				)
				(justify left bottom)
			)
		)
		(property "Value" "S27KL0641DABHI023"
			(at 0.1 5.3 90)
			(layer "F.Fab")
			(effects
				(font
					(size 0.7 0.7)
					(thickness 0.15)
				)
				(justify left bottom)
			)
		)
		(property "Author" "Antmicro"
			(at 247.972485 -53.420171 0)
			(layer "F.Fab")
			(hide yes)
			(effects
				(font
					(size 1 1)
					(thickness 0.15)
				)
			)
		)
		(property "License" "Apache-2.0"
			(at 247.972485 -53.420171 0)
			(layer "F.Fab")
			(hide yes)
			(effects
				(font
					(size 1 1)
					(thickness 0.15)
				)
			)
		)
		(property "MPN" "S27KL0641DABHI023"
			(at 247.972485 -53.420171 0)
			(layer "F.Fab")
			(hide yes)
			(effects
				(font
					(size 1 1)
					(thickness 0.15)
				)
			)
		)
		(property "Manufacturer" "Cypress Semiconductor"
			(at 247.972485 -53.420171 0)
			(layer "F.Fab")
			(hide yes)
			(effects
				(font
					(size 1 1)
					(thickness 0.15)
				)
			)
		)
		(sheetname "HyperRAM")
		(sheetfile "hyperram.kicad_sch")
		(attr smd)
		(fp_line
			(start 3.12 -4.121)
			(end 3.12 -2.121)
			(stroke
				(width 0.15)
				(type solid)
			)
			(layer "F.SilkS")
		)
		(fp_line
			(start 3.12 -4.121)
			(end 3.12 -2.121)
			(stroke
				(width 0.15)
				(type solid)
			)
			(layer "F.SilkS")
		)
		(fp_line
			(start 3.12 -4.121)
			(end 3.12 -2.121)
			(stroke
				(width 0.15)
				(type solid)
			)
			(layer "F.SilkS")
		)
		(fp_line
			(start 1.62 -4.121)
			(end 3.12 -4.121)
			(stroke
				(width 0.15)
				(type solid)
			)
			(layer "F.SilkS")
		)
		(fp_line
			(start 1.62 -4.121)
			(end 3.12 -4.121)
			(stroke
				(width 0.15)
				(type solid)
			)
			(layer "F.SilkS")
		)
		(fp_line
			(start 1.62 -4.121)
			(end 3.12 -4.121)
			(stroke
				(width 0.15)
				(type solid)
			)
			(layer "F.SilkS")
		)
		(fp_line
			(start -1.621 -4.121)
			(end -2 -4.121)
			(stroke
				(width 0.15)
				(type solid)
			)
			(layer "F.SilkS")
		)
		(fp_line
			(start -2 -4.121)
			(end -3.121 -3)
			(stroke
				(width 0.15)
				(type solid)
			)
			(layer "F.SilkS")
		)
		(fp_line
			(start -3.121 -3)
			(end -3.121 -2.121)
			(stroke
				(width 0.15)
				(type solid)
			)
			(layer "F.SilkS")
		)
		(fp_line
			(start 3.12 4.12)
			(end 3.12 2.12)
			(stroke
				(width 0.15)
				(type solid)
			)
			(layer "F.SilkS")
		)
		(fp_line
			(start 1.62 4.12)
			(end 3.12 4.12)
			(stroke
				(width 0.15)
				(type solid)
			)
			(layer "F.SilkS")
		)
		(fp_line
			(start -1.621 4.12)
			(end -3.121 4.12)
			(stroke
				(width 0.15)
				(type solid)
			)
			(layer "F.SilkS")
		)
		(fp_line
			(start -3.121 4.12)
			(end -3.121 2.12)
			(stroke
				(width 0.15)
				(type solid)
			)
			(layer "F.SilkS")
		)
		(fp_circle
			(center -3.6 -3.9)
			(end -3.5 -3.9)
			(stroke
				(width 0.15)
				(type solid)
			)
			(fill yes)
			(layer "F.SilkS")
		)
		(fp_line
			(start 3.24 -4.25)
			(end 3.24 4.24)
			(stroke
				(width 0.05)
				(type solid)
			)
			(layer "F.CrtYd")
		)
		(fp_line
			(start -3.25 -4.25)
			(end 3.24 -4.25)
			(stroke
				(width 0.05)
				(type solid)
			)
			(layer "F.CrtYd")
		)
		(fp_line
			(start 3.24 4.24)
			(end -3.25 4.24)
			(stroke
				(width 0.05)
				(type solid)
			)
			(layer "F.CrtYd")
		)
		(fp_line
			(start -3.25 4.24)
			(end -3.25 -4.25)
			(stroke
				(width 0.05)
				(type solid)
			)
			(layer "F.CrtYd")
		)
		(fp_line
			(start 2.999 -4)
			(end -2 -4)
			(stroke
				(width 0.15)
				(type solid)
			)
			(layer "F.Fab")
		)
		(fp_line
			(start -2 -4)
			(end -3 -3)
			(stroke
				(width 0.15)
				(type solid)
			)
			(layer "F.Fab")
		)
		(fp_line
			(start -3 -3)
			(end -3 3.999)
			(stroke
				(width 0.15)
				(type solid)
			)
			(layer "F.Fab")
		)
		(fp_line
			(start 2.999 3.999)
			(end 2.999 -4)
			(stroke
				(width 0.15)
				(type solid)
			)
			(layer "F.Fab")
		)
		(fp_line
			(start -3 3.999)
			(end 2.999 3.999)
			(stroke
				(width 0.15)
				(type solid)
			)
			(layer "F.Fab")
		)
		(pad "A2" smd circle
			(at -1 -2 90)
			(size 0.4 0.4)
			(layers "F.Cu" "F.Mask" "F.Paste")
			(net 266 "unconnected-(U1-NC-PadA2)")
			(pinfunction "NC")
			(pintype "no_connect")
		)
		(pad "A3" smd circle
			(at 0 -2 90)
			(size 0.4 0.4)
			(layers "F.Cu" "F.Mask" "F.Paste")
			(net 489 "HR_CS")
			(pinfunction "~{CS}")
			(pintype "input")
		)
		(pad "A4" smd circle
			(at 0.999 -2 90)
			(size 0.4 0.4)
			(layers "F.Cu" "F.Mask" "F.Paste")
			(net 488 "HR_RST")
			(pinfunction "~{RESET}")
			(pintype "input")
		)
		(pad "A5" smd circle
			(at 1.999 -2 90)
			(size 0.4 0.4)
			(layers "F.Cu" "F.Mask" "F.Paste")
			(net 267 "unconnected-(U1-NC-PadA5)")
			(pinfunction "NC")
			(pintype "no_connect")
		)
		(pad "B1" smd circle
			(at -2 -1 90)
			(size 0.4 0.4)
			(layers "F.Cu" "F.Mask" "F.Paste")
			(net 493 "HR_CKN")
			(pinfunction "CK-")
			(pintype "input")
		)
		(pad "B2" smd circle
			(at -1 -1 90)
			(size 0.4 0.4)
			(layers "F.Cu" "F.Mask" "F.Paste")
			(net 498 "HR_CKP")
			(pinfunction "CK+")
			(pintype "input")
		)
		(pad "B3" smd circle
			(at 0 -1 90)
			(size 0.4 0.4)
			(layers "F.Cu" "F.Mask" "F.Paste")
			(net 5 "GND")
			(pinfunction "VSS")
			(pintype "power_in")
		)
		(pad "B4" smd circle
			(at 0.999 -1 90)
			(size 0.4 0.4)
			(layers "F.Cu" "F.Mask" "F.Paste")
			(net 459 "3V3_SYS")
			(pinfunction "VCC")
			(pintype "power_in")
		)
		(pad "B5" smd circle
			(at 1.999 -1 90)
			(size 0.4 0.4)
			(layers "F.Cu" "F.Mask" "F.Paste")
			(net 268 "unconnected-(U1-NC-PadB5)")
			(pinfunction "NC")
			(pintype "no_connect")
		)
		(pad "C1" smd circle
			(at -2 0 90)
			(size 0.4 0.4)
			(layers "F.Cu" "F.Mask" "F.Paste")
			(net 5 "GND")
			(pinfunction "VSSQ")
			(pintype "power_in")
		)
		(pad "C2" smd circle
			(at -1 0 90)
			(size 0.4 0.4)
			(layers "F.Cu" "F.Mask" "F.Paste")
			(net 269 "unconnected-(U1-NC-PadC2)")
			(pinfunction "NC")
			(pintype "no_connect")
		)
		(pad "C3" smd circle
			(at 0 0 90)
			(size 0.4 0.4)
			(layers "F.Cu" "F.Mask" "F.Paste")
			(net 492 "HR_RW")
			(pinfunction "RWDS")
			(pintype "bidirectional")
		)
		(pad "C4" smd circle
			(at 0.999 0 90)
			(size 0.4 0.4)
			(layers "F.Cu" "F.Mask" "F.Paste")
			(net 500 "HR_DQ2")
			(pinfunction "DQ2")
			(pintype "bidirectional")
		)
		(pad "C5" smd circle
			(at 1.999 0 90)
			(size 0.4 0.4)
			(layers "F.Cu" "F.Mask" "F.Paste")
			(net 270 "unconnected-(U1-NC-PadC5)")
			(pinfunction "NC")
			(pintype "no_connect")
		)
		(pad "D1" smd circle
			(at -2 0.999 90)
			(size 0.4 0.4)
			(layers "F.Cu" "F.Mask" "F.Paste")
			(net 459 "3V3_SYS")
			(pinfunction "VCCQ")
			(pintype "power_in")
		)
		(pad "D2" smd circle
			(at -1 0.999 90)
			(size 0.4 0.4)
			(layers "F.Cu" "F.Mask" "F.Paste")
			(net 490 "HR_DQ1")
			(pinfunction "DQ1")
			(pintype "bidirectional")
		)
		(pad "D3" smd circle
			(at 0 0.999 90)
			(size 0.4 0.4)
			(layers "F.Cu" "F.Mask" "F.Paste")
			(net 491 "HR_DQ0")
			(pinfunction "DQ0")
			(pintype "bidirectional")
		)
		(pad "D4" smd circle
			(at 0.999 0.999 90)
			(size 0.4 0.4)
			(layers "F.Cu" "F.Mask" "F.Paste")
			(net 499 "HR_DQ3")
			(pinfunction "DQ3")
			(pintype "bidirectional")
		)
		(pad "D5" smd circle
			(at 1.999 0.999 90)
			(size 0.4 0.4)
			(layers "F.Cu" "F.Mask" "F.Paste")
			(net 495 "HR_DQ4")
			(pinfunction "DQ4")
			(pintype "bidirectional")
		)
		(pad "E1" smd circle
			(at -2 1.999 90)
			(size 0.4 0.4)
			(layers "F.Cu" "F.Mask" "F.Paste")
			(net 496 "HR_DQ7")
			(pinfunction "DQ7")
			(pintype "bidirectional")
		)
		(pad "E2" smd circle
			(at -1 1.999 90)
			(size 0.4 0.4)
			(layers "F.Cu" "F.Mask" "F.Paste")
			(net 497 "HR_DQ6")
			(pinfunction "DQ6")
			(pintype "bidirectional")
		)
		(pad "E3" smd circle
			(at 0 1.999 90)
			(size 0.4 0.4)
			(layers "F.Cu" "F.Mask" "F.Paste")
			(net 494 "HR_DQ5")
			(pinfunction "DQ5")
			(pintype "bidirectional")
		)
		(pad "E4" smd circle
			(at 0.999 1.999 90)
			(size 0.4 0.4)
			(layers "F.Cu" "F.Mask" "F.Paste")
			(net 459 "3V3_SYS")
			(pinfunction "VCCQ")
			(pintype "passive")
		)
		(pad "E5" smd circle
			(at 1.999 1.999 90)
			(size 0.4 0.4)
			(layers "F.Cu" "F.Mask" "F.Paste")
			(net 5 "GND")
			(pinfunction "VSSQ")
			(pintype "passive")
		)
	)
)
